(kicad_pcb
	(version 20260206)
	(generator "pcbnew")
	(generator_version "10.0")
	(general
		(thickness 1.6)
		(legacy_teardrops no)
	)
	(paper "A4")
	(title_block
		(title "baseboard — 13948-1b.1110WZS1818.brd")
		(comment 1 "Honey Badger (Wiwynn) / footprints 1577-1585 of 2523")
	)
	(layers
		(0 "F.Cu" signal "TOP")
		(4 "In1.Cu" signal "L2GND")
		(6 "In2.Cu" signal "L3")
		(8 "In3.Cu" signal "L4VCC")
		(10 "In4.Cu" signal "L5VCC")
		(12 "In5.Cu" signal "L6")
		(14 "In6.Cu" signal "L7GND")
		(2 "B.Cu" signal "BOTTOM")
		(9 "F.Adhes" user "F.Adhesive")
		(11 "B.Adhes" user "B.Adhesive")
		(13 "F.Paste" user "Package Geometry/Pastemask Top")
		(15 "B.Paste" user "Package Geometry/Pastemask Bottom")
		(5 "F.SilkS" user "Ref Des/Silkscreen Top")
		(7 "B.SilkS" user "Ref Des/Silkscreen Bottom")
		(1 "F.Mask" user "Board Geometry/Soldermask Top")
		(3 "B.Mask" user "Board Geometry/Soldermask Bottom")
		(17 "Dwgs.User" user "User.Drawings")
		(19 "Cmts.User" user "User.Comments")
		(21 "Eco1.User" user "User.Eco1")
		(23 "Eco2.User" user "User.Eco2")
		(25 "Edge.Cuts" user "Board Geometry/Outline")
		(27 "Margin" user)
		(31 "F.CrtYd" user "Package Geometry/Place Bound Top")
		(29 "B.CrtYd" user "Package Geometry/Place Bound Bottom")
		(35 "F.Fab" user "Ref Des/Assembly Top")
		(33 "B.Fab" user "Ref Des/Assembly Bottom")
	)
	(footprint ""
		(layer "F.Cu")
		(at 250.259596 -53.232812 -90)
		(property "Reference" "SR722"
			(at 0 0 270)
			(layer "F.SilkS")
			(hide yes)
			(effects
				(font
					(size 1.27 1.27)
				)
			)
		)
		(property "Value" "0R2J-2-GP"
			(at 0.064008 -3.993896 270)
			(unlocked yes)
			(layer "F.Fab")
			(hide yes)
			(effects
				(font
					(size 1.016 1.016)
					(thickness 0.1524)
				)
			)
		)
		(property "Device Type" "R402H16"
			(at 0.064008 -5.517896 270)
			(unlocked yes)
			(layer "F.Fab")
			(hide yes)
			(effects
				(font
					(size 1.016 1.016)
					(thickness 0.1524)
				)
			)
		)
		(duplicate_pad_numbers_are_jumpers no)
		(fp_line
			(start -0.508 -0.9398)
			(end -0.508 0.9398)
			(stroke
				(width 0.1524)
				(type default)
			)
			(layer "F.SilkS")
		)
		(fp_line
			(start 0.508 -0.9398)
			(end -0.508 -0.9398)
			(stroke
				(width 0.1524)
				(type default)
			)
			(layer "F.SilkS")
		)
		(fp_rect
			(start -0.508 0.9398)
			(end 0.508 -0.9398)
			(stroke
				(width 0)
				(type default)
			)
			(fill no)
			(layer "F.CrtYd")
		)
		(fp_rect
			(start -0.508 0.9398)
			(end 0.508 -0.9398)
			(stroke
				(width 0)
				(type default)
			)
			(fill no)
			(layer "F.Fab")
		)
		(pad "1" smd custom
			(at 0 -0.4445 270)
			(size 0.1397 0.1397)
			(layers "F.Cu" "F.Mask" "F.Paste")
			(net "IOC_EEPROM_SCL")
			(options
				(clearance outline)
				(anchor circle)
			)
			(primitives
				(gr_poly
					(pts
						(arc
							(start -0.1778 -0.2794)
							(mid -0.249642 -0.249642)
							(end -0.2794 -0.1778)
						)
						(arc
							(start -0.2794 0.1778)
							(mid -0.249642 0.249642)
							(end -0.1778 0.2794)
						)
						(arc
							(start 0.1778 0.2794)
							(mid 0.249642 0.249642)
							(end 0.2794 0.1778)
						)
						(arc
							(start 0.2794 -0.1778)
							(mid 0.249642 -0.249642)
							(end 0.1778 -0.2794)
						)
					)
					(width 0)
					(fill yes)
				)
			)
		)
		(pad "2" smd custom
			(at 0 0.4445 270)
			(size 0.1397 0.1397)
			(layers "F.Cu" "F.Mask" "F.Paste")
			(net "SBL_SCL")
			(options
				(clearance outline)
				(anchor circle)
			)
			(primitives
				(gr_poly
					(pts
						(arc
							(start -0.1778 -0.2794)
							(mid -0.249642 -0.249642)
							(end -0.2794 -0.1778)
						)
						(arc
							(start -0.2794 0.1778)
							(mid -0.249642 0.249642)
							(end -0.1778 0.2794)
						)
						(arc
							(start 0.1778 0.2794)
							(mid 0.249642 0.249642)
							(end 0.2794 0.1778)
						)
						(arc
							(start 0.2794 -0.1778)
							(mid 0.249642 -0.249642)
							(end 0.1778 -0.2794)
						)
					)
					(width 0)
					(fill yes)
				)
			)
		)
	)
	(footprint ""
		(layer "F.Cu")
		(at 48.895 -223.139 -90)
		(property "Reference" "R9022"
			(at 0 0 270)
			(layer "F.SilkS")
			(hide yes)
			(effects
				(font
					(size 1.27 1.27)
				)
			)
		)
		(property "Value" "86K6R2F-GP"
			(at 0.064008 -3.993896 270)
			(unlocked yes)
			(layer "F.Fab")
			(hide yes)
			(effects
				(font
					(size 1.016 1.016)
					(thickness 0.1524)
				)
			)
		)
		(property "Device Type" "R402H16"
			(at 0.064008 -5.517896 270)
			(unlocked yes)
			(layer "F.Fab")
			(hide yes)
			(effects
				(font
					(size 1.016 1.016)
					(thickness 0.1524)
				)
			)
		)
		(duplicate_pad_numbers_are_jumpers no)
		(fp_line
			(start -0.508 -0.9398)
			(end -0.508 0.9398)
			(stroke
				(width 0.1524)
				(type default)
			)
			(layer "F.SilkS")
		)
		(fp_line
			(start 0.508 -0.9398)
			(end -0.508 -0.9398)
			(stroke
				(width 0.1524)
				(type default)
			)
			(layer "F.SilkS")
		)
		(fp_rect
			(start -0.508 0.9398)
			(end 0.508 -0.9398)
			(stroke
				(width 0)
				(type default)
			)
			(fill no)
			(layer "F.CrtYd")
		)
		(fp_rect
			(start -0.508 0.9398)
			(end 0.508 -0.9398)
			(stroke
				(width 0)
				(type default)
			)
			(fill no)
			(layer "F.Fab")
		)
		(pad "1" smd custom
			(at 0 -0.4445 270)
			(size 0.1397 0.1397)
			(layers "F.Cu" "F.Mask" "F.Paste")
			(net "MB0_PSET_R")
			(options
				(clearance outline)
				(anchor circle)
			)
			(primitives
				(gr_poly
					(pts
						(arc
							(start -0.1778 -0.2794)
							(mid -0.249642 -0.249642)
							(end -0.2794 -0.1778)
						)
						(arc
							(start -0.2794 0.1778)
							(mid -0.249642 0.249642)
							(end -0.1778 0.2794)
						)
						(arc
							(start 0.1778 0.2794)
							(mid 0.249642 0.249642)
							(end 0.2794 0.1778)
						)
						(arc
							(start 0.2794 -0.1778)
							(mid 0.249642 -0.249642)
							(end 0.1778 -0.2794)
						)
					)
					(width 0)
					(fill yes)
				)
			)
		)
		(pad "2" smd custom
			(at 0 0.4445 270)
			(size 0.1397 0.1397)
			(layers "F.Cu" "F.Mask" "F.Paste")
			(net "AGND_CURRENT_MON")
			(options
				(clearance outline)
				(anchor circle)
			)
			(primitives
				(gr_poly
					(pts
						(arc
							(start -0.1778 -0.2794)
							(mid -0.249642 -0.249642)
							(end -0.2794 -0.1778)
						)
						(arc
							(start -0.2794 0.1778)
							(mid -0.249642 0.249642)
							(end -0.1778 0.2794)
						)
						(arc
							(start 0.1778 0.2794)
							(mid 0.249642 0.249642)
							(end 0.2794 0.1778)
						)
						(arc
							(start 0.2794 -0.1778)
							(mid 0.249642 -0.249642)
							(end 0.1778 -0.2794)
						)
					)
					(width 0)
					(fill yes)
				)
			)
		)
	)
	(footprint ""
		(layer "F.Cu")
		(at 109.97057 -78.6638 -90)
		(property "Reference" "STP63"
			(at 0 0 270)
			(layer "F.SilkS")
			(hide yes)
			(effects
				(font
					(size 1.27 1.27)
				)
			)
		)
		(property "Value" "TPAD28"
			(at 0.0127 -1.8034 270)
			(unlocked yes)
			(layer "F.Fab")
			(hide yes)
			(effects
				(font
					(size 1.016 1.016)
					(thickness 0.1524)
				)
			)
		)
		(property "Device Type" "TPAD28"
			(at 0.0127 -3.3274 270)
			(unlocked yes)
			(layer "F.Fab")
			(hide yes)
			(effects
				(font
					(size 1.016 1.016)
					(thickness 0.1524)
				)
			)
		)
		(duplicate_pad_numbers_are_jumpers no)
		(fp_poly
			(pts
				(arc
					(start 0 -0.3556)
					(mid 0 0.3556)
					(end 0 -0.3556)
				)
			)
			(stroke
				(width 0)
				(type default)
			)
			(fill no)
			(layer "F.CrtYd")
		)
		(fp_poly
			(pts
				(arc
					(start 0 -0.6096)
					(mid 0 0.6096)
					(end 0 -0.6096)
				)
			)
			(stroke
				(width 0)
				(type default)
			)
			(fill no)
			(layer "F.Fab")
		)
		(pad "1" smd circle
			(at 0 0 270)
			(size 0.7112 0.7112)
			(layers "F.Cu" "F.Mask" "F.Paste")
			(net "EXP_TEST_MUX25")
		)
	)
	(footprint ""
		(layer "F.Cu")
		(at 289.687 -69.723 -90)
		(property "Reference" "PR6888"
			(at 0 0 270)
			(layer "F.SilkS")
			(hide yes)
			(effects
				(font
					(size 1.27 1.27)
				)
			)
		)
		(property "Value" "5K36R2F-GP"
			(at 0.064008 -3.993896 270)
			(unlocked yes)
			(layer "F.Fab")
			(hide yes)
			(effects
				(font
					(size 1.016 1.016)
					(thickness 0.1524)
				)
			)
		)
		(property "Device Type" "R402H16"
			(at 0.064008 -5.517896 270)
			(unlocked yes)
			(layer "F.Fab")
			(hide yes)
			(effects
				(font
					(size 1.016 1.016)
					(thickness 0.1524)
				)
			)
		)
		(duplicate_pad_numbers_are_jumpers no)
		(fp_line
			(start -0.508 -0.9398)
			(end -0.508 0.9398)
			(stroke
				(width 0.1524)
				(type default)
			)
			(layer "F.SilkS")
		)
		(fp_line
			(start 0.508 -0.9398)
			(end -0.508 -0.9398)
			(stroke
				(width 0.1524)
				(type default)
			)
			(layer "F.SilkS")
		)
		(fp_rect
			(start -0.508 0.9398)
			(end 0.508 -0.9398)
			(stroke
				(width 0)
				(type default)
			)
			(fill no)
			(layer "F.CrtYd")
		)
		(fp_rect
			(start -0.508 0.9398)
			(end 0.508 -0.9398)
			(stroke
				(width 0)
				(type default)
			)
			(fill no)
			(layer "F.Fab")
		)
		(pad "1" smd custom
			(at 0 -0.4445 270)
			(size 0.1397 0.1397)
			(layers "F.Cu" "F.Mask" "F.Paste")
			(net "P12V_PCIE")
			(options
				(clearance outline)
				(anchor circle)
			)
			(primitives
				(gr_poly
					(pts
						(arc
							(start -0.1778 -0.2794)
							(mid -0.249642 -0.249642)
							(end -0.2794 -0.1778)
						)
						(arc
							(start -0.2794 0.1778)
							(mid -0.249642 0.249642)
							(end -0.1778 0.2794)
						)
						(arc
							(start 0.1778 0.2794)
							(mid 0.249642 0.249642)
							(end 0.2794 0.1778)
						)
						(arc
							(start 0.2794 -0.1778)
							(mid 0.249642 -0.249642)
							(end 0.1778 -0.2794)
						)
					)
					(width 0)
					(fill yes)
				)
			)
		)
		(pad "2" smd custom
			(at 0 0.4445 270)
			(size 0.1397 0.1397)
			(layers "F.Cu" "F.Mask" "F.Paste")
			(net "HS_ADR")
			(options
				(clearance outline)
				(anchor circle)
			)
			(primitives
				(gr_poly
					(pts
						(arc
							(start -0.1778 -0.2794)
							(mid -0.249642 -0.249642)
							(end -0.2794 -0.1778)
						)
						(arc
							(start -0.2794 0.1778)
							(mid -0.249642 0.249642)
							(end -0.1778 0.2794)
						)
						(arc
							(start 0.1778 0.2794)
							(mid 0.249642 0.249642)
							(end 0.2794 0.1778)
						)
						(arc
							(start 0.2794 -0.1778)
							(mid 0.249642 -0.249642)
							(end 0.1778 -0.2794)
						)
					)
					(width 0)
					(fill yes)
				)
			)
		)
	)
	(footprint ""
		(layer "F.Cu")
		(at 174.107348 -123.815856 90)
		(property "Reference" "PC170"
			(at 0 0 90)
			(layer "F.SilkS")
			(hide yes)
			(effects
				(font
					(size 1.27 1.27)
				)
			)
		)
		(property "Value" "SC22U25V5MX-GP"
			(at -0.0762 -6.1214 90)
			(unlocked yes)
			(layer "F.Fab")
			(hide yes)
			(effects
				(font
					(size 1.016 1.016)
					(thickness 0.1524)
				)
			)
		)
		(property "Device Type" "C805H58"
			(at -0.0762 -8.1534 90)
			(unlocked yes)
			(layer "F.Fab")
			(hide yes)
			(effects
				(font
					(size 1.016 1.016)
					(thickness 0.1524)
				)
			)
		)
		(duplicate_pad_numbers_are_jumpers no)
		(fp_line
			(start 0.635 0)
			(end -0.635 0)
			(stroke
				(width 0.508)
				(type default)
			)
			(layer "F.SilkS")
		)
		(fp_rect
			(start -0.9652 1.778)
			(end 0.9652 -1.778)
			(stroke
				(width 0)
				(type default)
			)
			(fill no)
			(layer "F.CrtYd")
		)
		(fp_poly
			(pts
				(xy -0.9652 -1.778) (xy 0.9652 -1.778) (xy 0.9652 1.778) (xy -0.9652 1.778)
			)
			(stroke
				(width 0)
				(type default)
			)
			(fill no)
			(layer "F.Fab")
		)
		(pad "1" smd rect
			(at 0 -0.9652 90)
			(size 1.397 1.143)
			(layers "F.Cu" "F.Mask" "F.Paste")
			(net "P0V9_E_VIN")
		)
		(pad "2" smd rect
			(at 0 0.9652 90)
			(size 1.397 1.143)
			(layers "F.Cu" "F.Mask" "F.Paste")
			(net "GND")
		)
	)
	(footprint ""
		(layer "F.Cu")
		(at 132.212842 -83.129882 90)
		(property "Reference" "SC1094"
			(at 0 0 90)
			(layer "F.SilkS")
			(hide yes)
			(effects
				(font
					(size 1.27 1.27)
				)
			)
		)
		(property "Value" "SCD01U10V1KX-GP"
			(at -2.8321 -1.7399 90)
			(unlocked yes)
			(layer "F.Fab")
			(hide yes)
			(effects
				(font
					(size 1.016 1.016)
					(thickness 0.1524)
				)
			)
		)
		(property "Device Type" "C0201H13"
			(at -2.8321 -3.2639 90)
			(unlocked yes)
			(layer "F.Fab")
			(hide yes)
			(effects
				(font
					(size 1.016 1.016)
					(thickness 0.1524)
				)
			)
		)
		(duplicate_pad_numbers_are_jumpers no)
		(fp_rect
			(start -0.2794 0.6477)
			(end 0.2794 -0.6477)
			(stroke
				(width 0)
				(type default)
			)
			(fill no)
			(layer "F.CrtYd")
		)
		(fp_rect
			(start -0.2794 0.6477)
			(end 0.2794 -0.6477)
			(stroke
				(width 0)
				(type default)
			)
			(fill no)
			(layer "F.Fab")
		)
		(pad "1" smd custom
			(at 0 -0.2794 90)
			(size 0.0762 0.0762)
			(layers "F.Cu" "F.Mask" "F.Paste")
			(net "SAS_HDD_TX13_P")
			(options
				(clearance outline)
				(anchor circle)
			)
			(primitives
				(gr_poly
					(pts
						(arc
							(start 0.1524 -0.127)
							(mid 0.137521 -0.162921)
							(end 0.1016 -0.1778)
						)
						(arc
							(start -0.1016 -0.1778)
							(mid -0.137521 -0.162921)
							(end -0.1524 -0.127)
						)
						(arc
							(start -0.1524 0.127)
							(mid -0.137521 0.162921)
							(end -0.1016 0.1778)
						)
						(arc
							(start 0.1016 0.1778)
							(mid 0.137521 0.162921)
							(end 0.1524 0.127)
						)
					)
					(width 0)
					(fill yes)
				)
			)
		)
		(pad "2" smd custom
			(at 0 0.2794 90)
			(size 0.0762 0.0762)
			(layers "F.Cu" "F.Mask" "F.Paste")
			(net "3008_SAS_RX_P1")
			(options
				(clearance outline)
				(anchor circle)
			)
			(primitives
				(gr_poly
					(pts
						(arc
							(start 0.1524 -0.127)
							(mid 0.137521 -0.162921)
							(end 0.1016 -0.1778)
						)
						(arc
							(start -0.1016 -0.1778)
							(mid -0.137521 -0.162921)
							(end -0.1524 -0.127)
						)
						(arc
							(start -0.1524 0.127)
							(mid -0.137521 0.162921)
							(end -0.1016 0.1778)
						)
						(arc
							(start 0.1016 0.1778)
							(mid 0.137521 0.162921)
							(end 0.1524 0.127)
						)
					)
					(width 0)
					(fill yes)
				)
			)
		)
	)
	(footprint ""
		(layer "F.Cu")
		(at 284.48 -161.163)
		(property "Reference" "TP135"
			(at 0 0 0)
			(layer "F.SilkS")
			(hide yes)
			(effects
				(font
					(size 1.27 1.27)
				)
			)
		)
		(property "Value" "TPAD28"
			(at 0.0127 -1.8034 0)
			(unlocked yes)
			(layer "F.Fab")
			(hide yes)
			(effects
				(font
					(size 1.016 1.016)
					(thickness 0.1524)
				)
			)
		)
		(property "Device Type" "TPAD28"
			(at 0.0127 -3.3274 0)
			(unlocked yes)
			(layer "F.Fab")
			(hide yes)
			(effects
				(font
					(size 1.016 1.016)
					(thickness 0.1524)
				)
			)
		)
		(duplicate_pad_numbers_are_jumpers no)
		(fp_poly
			(pts
				(arc
					(start 0.3556 0)
					(mid -0.3556 0)
					(end 0.3556 0)
				)
			)
			(stroke
				(width 0)
				(type default)
			)
			(fill no)
			(layer "F.CrtYd")
		)
		(fp_poly
			(pts
				(arc
					(start 0.6096 0)
					(mid -0.6096 0)
					(end 0.6096 0)
				)
			)
			(stroke
				(width 0)
				(type default)
			)
			(fill no)
			(layer "F.Fab")
		)
		(pad "1" smd circle
			(at 0 0)
			(size 0.7112 0.7112)
			(layers "F.Cu" "F.Mask" "F.Paste")
			(net "TP_BMC_GPIOF1")
		)
	)
	(footprint ""
		(layer "F.Cu")
		(at 333.912718 -148.948648 -90)
		(property "Reference" "R550"
			(at 0 0 270)
			(layer "F.SilkS")
			(hide yes)
			(effects
				(font
					(size 1.27 1.27)
				)
			)
		)
		(property "Value" "4K7R2F-GP"
			(at 0.064008 -3.993896 270)
			(unlocked yes)
			(layer "F.Fab")
			(hide yes)
			(effects
				(font
					(size 1.016 1.016)
					(thickness 0.1524)
				)
			)
		)
		(property "Device Type" "R402H16"
			(at 0.064008 -5.517896 270)
			(unlocked yes)
			(layer "F.Fab")
			(hide yes)
			(effects
				(font
					(size 1.016 1.016)
					(thickness 0.1524)
				)
			)
		)
		(duplicate_pad_numbers_are_jumpers no)
		(fp_line
			(start -0.508 -0.9398)
			(end -0.508 0.9398)
			(stroke
				(width 0.1524)
				(type default)
			)
			(layer "F.SilkS")
		)
		(fp_line
			(start 0.508 -0.9398)
			(end -0.508 -0.9398)
			(stroke
				(width 0.1524)
				(type default)
			)
			(layer "F.SilkS")
		)
		(fp_rect
			(start -0.508 0.9398)
			(end 0.508 -0.9398)
			(stroke
				(width 0)
				(type default)
			)
			(fill no)
			(layer "F.CrtYd")
		)
		(fp_rect
			(start -0.508 0.9398)
			(end 0.508 -0.9398)
			(stroke
				(width 0)
				(type default)
			)
			(fill no)
			(layer "F.Fab")
		)
		(pad "1" smd custom
			(at 0 -0.4445 270)
			(size 0.1397 0.1397)
			(layers "F.Cu" "F.Mask" "F.Paste")
			(net "CFG_SEL1")
			(options
				(clearance outline)
				(anchor circle)
			)
			(primitives
				(gr_poly
					(pts
						(arc
							(start -0.1778 -0.2794)
							(mid -0.249642 -0.249642)
							(end -0.2794 -0.1778)
						)
						(arc
							(start -0.2794 0.1778)
							(mid -0.249642 0.249642)
							(end -0.1778 0.2794)
						)
						(arc
							(start 0.1778 0.2794)
							(mid 0.249642 0.249642)
							(end 0.2794 0.1778)
						)
						(arc
							(start 0.2794 -0.1778)
							(mid 0.249642 -0.249642)
							(end 0.1778 -0.2794)
						)
					)
					(width 0)
					(fill yes)
				)
			)
		)
		(pad "2" smd custom
			(at 0 0.4445 270)
			(size 0.1397 0.1397)
			(layers "F.Cu" "F.Mask" "F.Paste")
			(net "GND")
			(options
				(clearance outline)
				(anchor circle)
			)
			(primitives
				(gr_poly
					(pts
						(arc
							(start -0.1778 -0.2794)
							(mid -0.249642 -0.249642)
							(end -0.2794 -0.1778)
						)
						(arc
							(start -0.2794 0.1778)
							(mid -0.249642 0.249642)
							(end -0.1778 0.2794)
						)
						(arc
							(start 0.1778 0.2794)
							(mid 0.249642 0.249642)
							(end 0.2794 0.1778)
						)
						(arc
							(start 0.2794 -0.1778)
							(mid 0.249642 -0.249642)
							(end 0.1778 -0.2794)
						)
					)
					(width 0)
					(fill yes)
				)
			)
		)
	)
	(footprint ""
		(layer "F.Cu")
		(at 319.396872 -119.452136 180)
		(property "Reference" "PC26"
			(at 0 0 180)
			(layer "F.SilkS")
			(hide yes)
			(effects
				(font
					(size 1.27 1.27)
				)
			)
		)
		(property "Value" "SC4D7U25V5KX-1-GP"
			(at -0.0762 -6.1214 180)
			(unlocked yes)
			(layer "F.Fab")
			(hide yes)
			(effects
				(font
					(size 1.016 1.016)
					(thickness 0.1524)
				)
			)
		)
		(property "Device Type" "C805H58"
			(at -0.0762 -8.1534 180)
			(unlocked yes)
			(layer "F.Fab")
			(hide yes)
			(effects
				(font
					(size 1.016 1.016)
					(thickness 0.1524)
				)
			)
		)
		(duplicate_pad_numbers_are_jumpers no)
		(fp_line
			(start 0.635 0)
			(end -0.635 0)
			(stroke
				(width 0.508)
				(type default)
			)
			(layer "F.SilkS")
		)
		(fp_rect
			(start -0.9652 1.778)
			(end 0.9652 -1.778)
			(stroke
				(width 0)
				(type default)
			)
			(fill no)
			(layer "F.CrtYd")
		)
		(fp_poly
			(pts
				(xy -0.9652 -1.778) (xy 0.9652 -1.778) (xy 0.9652 1.778) (xy -0.9652 1.778)
			)
			(stroke
				(width 0)
				(type default)
			)
			(fill no)
			(layer "F.Fab")
		)
		(pad "1" smd rect
			(at 0 -0.9652 180)
			(size 1.397 1.143)
			(layers "F.Cu" "F.Mask" "F.Paste")
			(net "P3V3_STBY_VDD")
		)
		(pad "2" smd rect
			(at 0 0.9652 180)
			(size 1.397 1.143)
			(layers "F.Cu" "F.Mask" "F.Paste")
			(net "GND")
		)
	)
)
